# TIMECARD (Time Appliance Project (Time Card)) — schematic netlist excerpt (pin names and nets, part order shuffled) for the footprints in the layout excerpt that follows; sources: Cadence DE-HDL packaged netlist, KiCad conversion of R4006-B0001-02_R01.brd

R85  RESISTOR  0OHM -  pkg SMC_0402R_H016  page 21 : \1\ = FPGA_OUT_MAC_PPS_IN0P ; \2\ = R_MAC_PPS_IN0P
R387  RESISTOR  33OHM 1%  pkg SMC_0402R_H016  page 26 : \1\ = SMA1_LED_RED_N ; \2\ = UNNAMED_14_LED4PV14_I265_3

(kicad_pcb
	(version 20260206)
	(generator "pcbnew")
	(generator_version "10.0")
	(general
		(thickness 1.6)
		(legacy_teardrops no)
	)
	(paper "A4")
	(title_block
		(title "timecard-production-celestica-r4006 — R4006-B0001-02_R01.brd")
		(comment 1 "Time Appliance Project (Time Card) / footprints 328-329 of 1113")
	)
	(layers
		(0 "F.Cu" signal "TOP")
		(4 "In1.Cu" signal "L02_GND1")
		(6 "In2.Cu" signal "L03_SIG1")
		(8 "In3.Cu" signal "L04_GND2")
		(10 "In4.Cu" signal "L05_VCC1")
		(12 "In5.Cu" signal "L06_VCC2")
		(14 "In6.Cu" signal "L07_GND3")
		(16 "In7.Cu" signal "L08_SIG2")
		(18 "In8.Cu" signal "L09_GND4")
		(2 "B.Cu" signal "BOTTOM")
		(9 "F.Adhes" user "F.Adhesive")
		(11 "B.Adhes" user "B.Adhesive")
		(13 "F.Paste" user "Package Geometry/Pastemask Top")
		(15 "B.Paste" user "Package Geometry/Pastemask Bottom")
		(5 "F.SilkS" user "Ref Des/Silkscreen Top")
		(7 "B.SilkS" user "Ref Des/Silkscreen Bottom")
		(1 "F.Mask" user "Board Geometry/Soldermask Top")
		(3 "B.Mask" user "Board Geometry/Soldermask Bottom")
		(17 "Dwgs.User" user "User.Drawings")
		(19 "Cmts.User" user "User.Comments")
		(21 "Eco1.User" user "User.Eco1")
		(23 "Eco2.User" user "User.Eco2")
		(25 "Edge.Cuts" user "Board Geometry/Outline")
		(27 "Margin" user)
		(31 "F.CrtYd" user "Package Geometry/Place Bound Top")
		(29 "B.CrtYd" user "Package Geometry/Place Bound Bottom")
		(35 "F.Fab" user "Ref Des/Assembly Top")
		(33 "B.Fab" user "Ref Des/Assembly Bottom")
	)
	(footprint ""
		(layer "F.Cu")
		(at 8.2804 -39.318692 90)
		(property "Reference" "R387"
			(at 2.337308 -0.04445 90)
			(unlocked yes)
			(layer "F.SilkS")
			(effects
				(font
					(size 0.635 0.4064)
					(thickness 0.1524)
				)
			)
		)
		(property "Value" "VAL*"
			(at 0.02032 2.13233 90)
			(unlocked yes)
			(layer "F.Fab")
			(hide yes)
			(effects
				(font
					(size 0.7874 0.5842)
					(thickness 0.1524)
				)
			)
		)
		(property "Tolerance" "TOL*"
			(at 0.044704 3.05435 90)
			(unlocked yes)
			(layer "Cmts.User")
			(hide yes)
			(effects
				(font
					(size 0.7874 0.5842)
					(thickness 0.1524)
				)
			)
		)
		(property "User Part Number" "PARTNUM*"
			(at 0.02032 4.024884 90)
			(unlocked yes)
			(layer "Cmts.User")
			(hide yes)
			(effects
				(font
					(size 0.7874 0.5842)
					(thickness 0.1524)
				)
			)
		)
		(property "Device Type" "RESISTOR-G155-133R0-01,33OHM,1%"
			(at 0.008382 1.210564 90)
			(unlocked yes)
			(layer "F.Fab")
			(hide yes)
			(effects
				(font
					(size 0.7874 0.5842)
					(thickness 0.1524)
				)
			)
		)
		(duplicate_pad_numbers_are_jumpers no)
		(fp_line
			(start 1.143 -0.5588)
			(end -1.143 -0.5588)
			(stroke
				(width 0.1)
				(type default)
			)
			(layer "F.SilkS")
		)
		(fp_line
			(start -1.143 -0.5588)
			(end -1.143 0.5588)
			(stroke
				(width 0.1)
				(type default)
			)
			(layer "F.SilkS")
		)
		(fp_line
			(start 1.143 0.5588)
			(end 1.143 -0.5588)
			(stroke
				(width 0.1)
				(type default)
			)
			(layer "F.SilkS")
		)
		(fp_line
			(start -1.143 0.5588)
			(end 1.143 0.5588)
			(stroke
				(width 0.1)
				(type default)
			)
			(layer "F.SilkS")
		)
		(fp_rect
			(start -1.143 -0.5588)
			(end 1.143 0.5588)
			(stroke
				(width 0)
				(type default)
			)
			(fill no)
			(layer "F.CrtYd")
		)
		(fp_line
			(start 0.508 -0.3048)
			(end -0.508 -0.3048)
			(stroke
				(width 0.1)
				(type default)
			)
			(layer "F.Fab")
		)
		(fp_line
			(start -0.508 -0.3048)
			(end -0.508 0.3048)
			(stroke
				(width 0.1)
				(type default)
			)
			(layer "F.Fab")
		)
		(fp_line
			(start 0.508 0.3048)
			(end 0.508 -0.3048)
			(stroke
				(width 0.1)
				(type default)
			)
			(layer "F.Fab")
		)
		(fp_line
			(start -0.508 0.3048)
			(end 0.508 0.3048)
			(stroke
				(width 0.1)
				(type default)
			)
			(layer "F.Fab")
		)
		(pad "1" smd rect
			(at -0.5334 0 90)
			(size 0.7112 0.6096)
			(layers "F.Cu" "F.Mask" "F.Paste")
			(net "SMA1_LED_RED_N")
		)
		(pad "2" smd rect
			(at 0.5334 0 90)
			(size 0.7112 0.6096)
			(layers "F.Cu" "F.Mask" "F.Paste")
			(net "UNNAMED_14_LED4PV14_I265_3")
		)
		(zone
			(layer "F.Cu")
			(hatch none 0.5)
			(connect_pads
				(clearance 0)
			)
			(min_thickness 0.25)
			(keepout
				(tracks not_allowed)
				(vias allowed)
				(pads allowed)
				(copperpour not_allowed)
				(footprints allowed)
			)
			(placement
				(enabled no)
				(sheetname "")
			)
			(fill
				(thermal_gap 0.5)
				(thermal_bridge_width 0.5)
				(island_removal_mode 0)
			)
			(polygon
				(pts
					(xy 7.9756 -39.242492) (xy 8.5852 -39.242492) (xy 8.5852 -39.394892) (xy 7.9756 -39.394892)
				)
			)
		)
		(zone
			(layer "F.Cu")
			(hatch none 0.5)
			(connect_pads
				(clearance 0)
			)
			(min_thickness 0.25)
			(keepout
				(tracks allowed)
				(vias not_allowed)
				(pads allowed)
				(copperpour not_allowed)
				(footprints allowed)
			)
			(placement
				(enabled no)
				(sheetname "")
			)
			(fill
				(thermal_gap 0.5)
				(thermal_bridge_width 0.5)
				(island_removal_mode 0)
			)
			(polygon
				(pts
					(xy 7.9756 -39.242492) (xy 8.5852 -39.242492) (xy 8.5852 -39.394892) (xy 7.9756 -39.394892)
				)
			)
		)
	)
	(footprint ""
		(layer "F.Cu")
		(at 81.0006 -51.181 180)
		(property "Reference" "R85"
			(at 0.9906 -14.88567 0)
			(unlocked yes)
			(layer "F.SilkS")
			(effects
				(font
					(size 0.7874 0.5842)
					(thickness 0.1524)
				)
			)
		)
		(property "Value" "VAL*"
			(at 0.02032 2.13233 180)
			(unlocked yes)
			(layer "F.Fab")
			(hide yes)
			(effects
				(font
					(size 0.7874 0.5842)
					(thickness 0.1524)
				)
			)
		)
		(property "Tolerance" "TOL*"
			(at 0.044704 3.05435 180)
			(unlocked yes)
			(layer "Cmts.User")
			(hide yes)
			(effects
				(font
					(size 0.7874 0.5842)
					(thickness 0.1524)
				)
			)
		)
		(property "User Part Number" "PARTNUM*"
			(at 0.02032 4.024884 180)
			(unlocked yes)
			(layer "Cmts.User")
			(hide yes)
			(effects
				(font
					(size 0.7874 0.5842)
					(thickness 0.1524)
				)
			)
		)
		(property "Device Type" "RESISTOR-G155-100R0-J0,0OHM,-"
			(at 0.008382 1.210564 180)
			(unlocked yes)
			(layer "F.Fab")
			(hide yes)
			(effects
				(font
					(size 0.7874 0.5842)
					(thickness 0.1524)
				)
			)
		)
		(duplicate_pad_numbers_are_jumpers no)
		(fp_line
			(start 1.143 0.5588)
			(end 1.143 -0.5588)
			(stroke
				(width 0.1)
				(type default)
			)
			(layer "F.SilkS")
		)
		(fp_line
			(start 1.143 -0.5588)
			(end -1.143 -0.5588)
			(stroke
				(width 0.1)
				(type default)
			)
			(layer "F.SilkS")
		)
		(fp_line
			(start -1.143 0.5588)
			(end 1.143 0.5588)
			(stroke
				(width 0.1)
				(type default)
			)
			(layer "F.SilkS")
		)
		(fp_line
			(start -1.143 -0.5588)
			(end -1.143 0.5588)
			(stroke
				(width 0.1)
				(type default)
			)
			(layer "F.SilkS")
		)
		(fp_rect
			(start 1.143 -0.5588)
			(end -1.143 0.5588)
			(stroke
				(width 0)
				(type default)
			)
			(fill no)
			(layer "F.CrtYd")
		)
		(fp_line
			(start 0.508 0.3048)
			(end 0.508 -0.3048)
			(stroke
				(width 0.1)
				(type default)
			)
			(layer "F.Fab")
		)
		(fp_line
			(start 0.508 -0.3048)
			(end -0.508 -0.3048)
			(stroke
				(width 0.1)
				(type default)
			)
			(layer "F.Fab")
		)
		(fp_line
			(start -0.508 0.3048)
			(end 0.508 0.3048)
			(stroke
				(width 0.1)
				(type default)
			)
			(layer "F.Fab")
		)
		(fp_line
			(start -0.508 -0.3048)
			(end -0.508 0.3048)
			(stroke
				(width 0.1)
				(type default)
			)
			(layer "F.Fab")
		)
		(pad "1" smd rect
			(at -0.5334 0 180)
			(size 0.7112 0.6096)
			(layers "F.Cu" "F.Mask" "F.Paste")
			(net "FPGA_OUT_MAC_PPS_IN0P")
		)
		(pad "2" smd rect
			(at 0.5334 0 180)
			(size 0.7112 0.6096)
			(layers "F.Cu" "F.Mask" "F.Paste")
			(net "R_MAC_PPS_IN0P")
		)
		(zone
			(layer "F.Cu")
			(hatch none 0.5)
			(connect_pads
				(clearance 0)
			)
			(min_thickness 0.25)
			(keepout
				(tracks allowed)
				(vias not_allowed)
				(pads allowed)
				(copperpour not_allowed)
				(footprints allowed)
			)
			(placement
				(enabled no)
				(sheetname "")
			)
			(fill
				(thermal_gap 0.5)
				(thermal_bridge_width 0.5)
				(island_removal_mode 0)
			)
			(polygon
				(pts
					(xy 80.9244 -50.8762) (xy 81.0768 -50.8762) (xy 81.0768 -51.4858) (xy 80.9244 -51.4858)
				)
			)
		)
	)
)
